(kicad_pcb
	(version 20260206)
	(generator "pcbnew")
	(generator_version "10.0")
	(general
		(thickness 1.6)
		(legacy_teardrops no)
	)
	(paper "A4")
	(title_block
		(title "Wiwynn_Tioga_Pass_MB.brd")
		(comment 1 "Tioga Pass / footprints 1861-1865 of 4770")
	)
	(layers
		(0 "F.Cu" signal "TOP")
		(4 "In1.Cu" signal "L2GND")
		(6 "In2.Cu" signal "L3")
		(8 "In3.Cu" signal "L4GND")
		(10 "In4.Cu" signal "L5")
		(12 "In5.Cu" signal "L6GND")
		(14 "In6.Cu" signal "L7VCC")
		(16 "In7.Cu" signal "L8VCC")
		(18 "In8.Cu" signal "L9GND")
		(20 "In9.Cu" signal "L10")
		(22 "In10.Cu" signal "L11GND")
		(24 "In11.Cu" signal "L12")
		(26 "In12.Cu" signal "L13GND")
		(2 "B.Cu" signal "BOTTOM")
		(9 "F.Adhes" user "F.Adhesive")
		(11 "B.Adhes" user "B.Adhesive")
		(13 "F.Paste" user "Package Geometry/Pastemask Top")
		(15 "B.Paste" user "Package Geometry/Pastemask Bottom")
		(5 "F.SilkS" user "Ref Des/Silkscreen Top")
		(7 "B.SilkS" user "Ref Des/Silkscreen Bottom")
		(1 "F.Mask" user "Board Geometry/Soldermask Top")
		(3 "B.Mask" user "Board Geometry/Soldermask Bottom")
		(17 "Dwgs.User" user "User.Drawings")
		(19 "Cmts.User" user "User.Comments")
		(21 "Eco1.User" user "User.Eco1")
		(23 "Eco2.User" user "User.Eco2")
		(25 "Edge.Cuts" user "Board Geometry/Outline")
		(27 "Margin" user)
		(31 "F.CrtYd" user "Package Geometry/Place Bound Top")
		(29 "B.CrtYd" user "Package Geometry/Place Bound Bottom")
		(35 "F.Fab" user "Ref Des/Assembly Top")
		(33 "B.Fab" user "Ref Des/Assembly Bottom")
	)
	(footprint ""
		(layer "F.Cu")
		(at 399.542 -77.089 180)
		(property "Reference" "CR8E1"
			(at 1.49733 1.4478 90)
			(unlocked yes)
			(layer "F.SilkS")
			(effects
				(font
					(size 0.7874 0.5842)
					(thickness 0.1524)
				)
				(justify left)
			)
		)
		(property "Value" ""
			(at 0 0 180)
			(layer "F.Fab")
			(effects
				(font
					(size 1.27 1.27)
				)
			)
		)
		(duplicate_pad_numbers_are_jumpers no)
		(fp_line
			(start -0.798576 1.649222)
			(end -1.279398 1.649222)
			(stroke
				(width 0.1524)
				(type default)
			)
			(layer "F.SilkS")
		)
		(fp_line
			(start -0.798576 0.816356)
			(end -1.76022 0.816356)
			(stroke
				(width 0.1524)
				(type default)
			)
			(layer "F.SilkS")
		)
		(fp_line
			(start -1.279398 2.560828)
			(end -1.279398 1.649222)
			(stroke
				(width 0.1524)
				(type default)
			)
			(layer "F.SilkS")
		)
		(fp_line
			(start -1.279398 1.649222)
			(end -1.76022 1.649222)
			(stroke
				(width 0.1524)
				(type default)
			)
			(layer "F.SilkS")
		)
		(fp_line
			(start -1.279398 0.816356)
			(end -0.798576 1.649222)
			(stroke
				(width 0.1524)
				(type default)
			)
			(layer "F.SilkS")
		)
		(fp_line
			(start -1.279398 -0.307086)
			(end -1.279398 0.816356)
			(stroke
				(width 0.1524)
				(type default)
			)
			(layer "F.SilkS")
		)
		(fp_line
			(start -1.76022 1.649222)
			(end -1.279398 0.816356)
			(stroke
				(width 0.1524)
				(type default)
			)
			(layer "F.SilkS")
		)
		(fp_poly
			(pts
				(xy -0.67437 0.24384) (xy -0.67437 2.04216) (xy 0.67437 2.04216) (xy 0.67437 0.24384)
			)
			(stroke
				(width 0)
				(type default)
			)
			(fill no)
			(layer "F.CrtYd")
		)
		(fp_line
			(start 0.67437 2.04216)
			(end 0.67437 0.24384)
			(stroke
				(width 0.1)
				(type default)
			)
			(layer "F.Fab")
		)
		(fp_line
			(start 0.67437 0.24384)
			(end -0.67437 0.24384)
			(stroke
				(width 0.1)
				(type default)
			)
			(layer "F.Fab")
		)
		(fp_line
			(start -0.67437 2.04216)
			(end 0.67437 2.04216)
			(stroke
				(width 0.1)
				(type default)
			)
			(layer "F.Fab")
		)
		(fp_line
			(start -0.67437 0.24384)
			(end -0.67437 2.04216)
			(stroke
				(width 0.1)
				(type default)
			)
			(layer "F.Fab")
		)
		(fp_line
			(start -0.803656 1.664462)
			(end -1.7653 1.664462)
			(stroke
				(width 0.1)
				(type default)
			)
			(layer "F.Fab")
		)
		(fp_line
			(start -0.854456 0.831596)
			(end -1.8161 0.831596)
			(stroke
				(width 0.1)
				(type default)
			)
			(layer "F.Fab")
		)
		(fp_line
			(start -1.284478 1.664462)
			(end -1.284478 2.576068)
			(stroke
				(width 0.1)
				(type default)
			)
			(layer "F.Fab")
		)
		(fp_line
			(start -1.284478 0.831596)
			(end -0.803656 1.664462)
			(stroke
				(width 0.1)
				(type default)
			)
			(layer "F.Fab")
		)
		(fp_line
			(start -1.335278 0.831596)
			(end -1.335278 -0.291846)
			(stroke
				(width 0.1)
				(type default)
			)
			(layer "F.Fab")
		)
		(fp_line
			(start -1.7653 1.664462)
			(end -1.284478 0.831596)
			(stroke
				(width 0.1)
				(type default)
			)
			(layer "F.Fab")
		)
		(pad "1" smd rect
			(at 0 0 180)
			(size 0.4064 1.016)
			(layers "F.Cu" "F.Mask" "F.Paste")
			(net "PWRGD_P12V_HSC")
		)
		(pad "2" smd rect
			(at 0 2.286 180)
			(size 0.4064 1.016)
			(layers "F.Cu" "F.Mask" "F.Paste")
			(net "PWRGD_P12V_HSC_DLY")
		)
	)
	(footprint ""
		(layer "F.Cu")
		(at 354.244656 -137.833608 180)
		(property "Reference" "R12W10"
			(at 0 0 180)
			(layer "F.SilkS")
			(hide yes)
			(effects
				(font
					(size 1.27 1.27)
				)
			)
		)
		(property "Value" "*"
			(at 0.064008 -4.108196 180)
			(unlocked yes)
			(layer "F.Fab")
			(hide yes)
			(effects
				(font
					(size 1.27 1.016)
					(thickness 0.1524)
				)
			)
		)
		(property "Device Type" "665KR2B-GP_SMD-RG2-665KR2B-GP,A"
			(at 0.064008 -5.632196 180)
			(unlocked yes)
			(layer "F.Fab")
			(hide yes)
			(effects
				(font
					(size 1.27 1.016)
					(thickness 0.1524)
				)
			)
		)
		(duplicate_pad_numbers_are_jumpers no)
		(fp_line
			(start 0.508 -0.9398)
			(end -0.508 -0.9398)
			(stroke
				(width 0.1524)
				(type default)
			)
			(layer "F.SilkS")
		)
		(fp_line
			(start -0.508 -0.9398)
			(end -0.508 0.9398)
			(stroke
				(width 0.1524)
				(type default)
			)
			(layer "F.SilkS")
		)
		(fp_rect
			(start -0.508 0.9398)
			(end 0.508 -0.9398)
			(stroke
				(width 0)
				(type default)
			)
			(fill no)
			(layer "F.CrtYd")
		)
		(fp_rect
			(start -0.508 0.9398)
			(end 0.508 -0.9398)
			(stroke
				(width 0)
				(type default)
			)
			(fill no)
			(layer "F.Fab")
		)
		(pad "1" smd custom
			(at 0 -0.4445 180)
			(size 0.1397 0.1397)
			(layers "F.Cu" "F.Mask" "F.Paste")
			(net "VR_PVDDQ_DEF_AIINSEN")
			(options
				(clearance outline)
				(anchor circle)
			)
			(primitives
				(gr_poly
					(pts
						(arc
							(start -0.1778 -0.2794)
							(mid -0.249642 -0.249642)
							(end -0.2794 -0.1778)
						)
						(arc
							(start -0.2794 0.1778)
							(mid -0.249642 0.249642)
							(end -0.1778 0.2794)
						)
						(arc
							(start 0.1778 0.2794)
							(mid 0.249642 0.249642)
							(end 0.2794 0.1778)
						)
						(arc
							(start 0.2794 -0.1778)
							(mid 0.249642 -0.249642)
							(end 0.1778 -0.2794)
						)
					)
					(width 0)
					(fill yes)
				)
			)
		)
		(pad "2" smd custom
			(at 0 0.4445 180)
			(size 0.1397 0.1397)
			(layers "F.Cu" "F.Mask" "F.Paste")
			(net "VR_PVDDQ_DEF_VINSEN")
			(options
				(clearance outline)
				(anchor circle)
			)
			(primitives
				(gr_poly
					(pts
						(arc
							(start -0.1778 -0.2794)
							(mid -0.249642 -0.249642)
							(end -0.2794 -0.1778)
						)
						(arc
							(start -0.2794 0.1778)
							(mid -0.249642 0.249642)
							(end -0.1778 0.2794)
						)
						(arc
							(start 0.1778 0.2794)
							(mid 0.249642 0.249642)
							(end 0.2794 0.1778)
						)
						(arc
							(start 0.2794 -0.1778)
							(mid 0.249642 -0.249642)
							(end 0.1778 -0.2794)
						)
					)
					(width 0)
					(fill yes)
				)
			)
		)
	)
	(footprint ""
		(layer "F.Cu")
		(at 339.092032 -129.587498 90)
		(property "Reference" "R7B9"
			(at 0 0 90)
			(layer "F.SilkS")
			(hide yes)
			(effects
				(font
					(size 1.27 1.27)
				)
			)
		)
		(property "Value" ""
			(at 0 0 90)
			(layer "F.Fab")
			(effects
				(font
					(size 1.27 1.27)
				)
			)
		)
		(duplicate_pad_numbers_are_jumpers no)
		(fp_poly
			(pts
				(xy -0.2794 -0.1016) (xy 0.2794 -0.1016) (xy 0.2794 0.9906) (xy -0.2794 0.9906)
			)
			(stroke
				(width 0)
				(type default)
			)
			(fill no)
			(layer "F.CrtYd")
		)
		(fp_line
			(start 0.2794 -0.1016)
			(end -0.2794 -0.1016)
			(stroke
				(width 0.1)
				(type default)
			)
			(layer "F.Fab")
		)
		(fp_line
			(start -0.2794 -0.1016)
			(end -0.2794 0.9906)
			(stroke
				(width 0.1)
				(type default)
			)
			(layer "F.Fab")
		)
		(fp_line
			(start 0.2794 0.9906)
			(end 0.2794 -0.1016)
			(stroke
				(width 0.1)
				(type default)
			)
			(layer "F.Fab")
		)
		(fp_line
			(start -0.2794 0.9906)
			(end 0.2794 0.9906)
			(stroke
				(width 0.1)
				(type default)
			)
			(layer "F.Fab")
		)
		(pad "1" smd rect
			(at 0 0 90)
			(size 0.508 0.508)
			(layers "F.Cu" "F.Mask" "F.Paste")
			(net "FM_PVPP_CPU0_EN")
		)
		(pad "2" smd rect
			(at 0 0.889 90)
			(size 0.508 0.508)
			(layers "F.Cu" "F.Mask" "F.Paste")
			(net "FM_PVPP_PVDDQ_CPU0_EN_DEF")
		)
		(zone
			(layer "F.Cu")
			(hatch none 0.5)
			(connect_pads
				(clearance 0)
			)
			(min_thickness 0.25)
			(keepout
				(tracks allowed)
				(vias not_allowed)
				(pads allowed)
				(copperpour not_allowed)
				(footprints allowed)
			)
			(placement
				(enabled no)
				(sheetname "")
			)
			(fill
				(thermal_gap 0.5)
				(thermal_bridge_width 0.5)
				(island_removal_mode 0)
			)
			(polygon
				(pts
					(xy 339.346032 -129.333498) (xy 339.346032 -129.841498) (xy 339.727032 -129.841498) (xy 339.727032 -129.333498)
				)
			)
		)
		(zone
			(layer "F.Cu")
			(hatch none 0.5)
			(connect_pads
				(clearance 0)
			)
			(min_thickness 0.25)
			(keepout
				(tracks not_allowed)
				(vias allowed)
				(pads allowed)
				(copperpour not_allowed)
				(footprints allowed)
			)
			(placement
				(enabled no)
				(sheetname "")
			)
			(fill
				(thermal_gap 0.5)
				(thermal_bridge_width 0.5)
				(island_removal_mode 0)
			)
			(polygon
				(pts
					(xy 339.727032 -129.333498) (xy 339.727032 -129.841498) (xy 339.346032 -129.841498) (xy 339.346032 -129.333498)
				)
			)
		)
	)
	(footprint ""
		(layer "F.Cu")
		(at 456.1713 -27.432 90)
		(property "Reference" "Q9F1"
			(at 0.92202 -1.23317 90)
			(unlocked yes)
			(layer "F.SilkS")
			(effects
				(font
					(size 0.7874 0.5842)
					(thickness 0.1524)
				)
				(justify left)
			)
		)
		(property "Value" ""
			(at 0 0 90)
			(layer "F.Fab")
			(effects
				(font
					(size 1.27 1.27)
				)
			)
		)
		(duplicate_pad_numbers_are_jumpers no)
		(fp_circle
			(center -0.788416 -0.597662)
			(end -0.788416 -0.470662)
			(stroke
				(width 0.254)
				(type default)
			)
			(fill no)
			(layer "F.SilkS")
		)
		(fp_poly
			(pts
				(xy 0.2159 1.7526) (xy 1.5621 1.7526) (xy 1.5621 -0.4572) (xy 0.2159 -0.4572)
			)
			(stroke
				(width 0)
				(type default)
			)
			(fill no)
			(layer "F.CrtYd")
		)
		(fp_line
			(start 1.5621 -0.45466)
			(end 0.2159 -0.45466)
			(stroke
				(width 0.1)
				(type default)
			)
			(layer "F.Fab")
		)
		(fp_line
			(start 0.2159 -0.45466)
			(end 0.2159 1.75514)
			(stroke
				(width 0.1)
				(type default)
			)
			(layer "F.Fab")
		)
		(fp_line
			(start 1.5621 1.75514)
			(end 1.5621 -0.45466)
			(stroke
				(width 0.1)
				(type default)
			)
			(layer "F.Fab")
		)
		(fp_line
			(start 0.2159 1.75514)
			(end 1.5621 1.75514)
			(stroke
				(width 0.1)
				(type default)
			)
			(layer "F.Fab")
		)
		(fp_circle
			(center -0.508 -0.7874)
			(end -0.508 -0.6604)
			(stroke
				(width 0.254)
				(type default)
			)
			(fill no)
			(layer "F.Fab")
		)
		(pad "1" smd rect
			(at 0 0 90)
			(size 1.016 0.381)
			(layers "F.Cu" "F.Mask" "F.Paste")
			(net "GND")
		)
		(pad "2" smd rect
			(at 0 0.65024 90)
			(size 1.016 0.381)
			(layers "F.Cu" "F.Mask" "F.Paste")
			(net "FM_BMC_FAULT_LED_N")
		)
		(pad "3" smd rect
			(at 0 1.30048 90)
			(size 1.016 0.381)
			(layers "F.Cu" "F.Mask" "F.Paste")
			(net "FM_RED_LED_CATHODE")
		)
		(pad "4" smd rect
			(at 1.778 1.30048 90)
			(size 1.016 0.381)
			(layers "F.Cu" "F.Mask" "F.Paste")
			(net "GND")
		)
		(pad "5" smd rect
			(at 1.778 0.65024 90)
			(size 1.016 0.381)
			(layers "F.Cu" "F.Mask" "F.Paste")
			(net "FM_BMC_FAULT_LED")
		)
		(pad "6" smd rect
			(at 1.778 0 90)
			(size 1.016 0.381)
			(layers "F.Cu" "F.Mask" "F.Paste")
			(net "FM_BMC_FAULT_LED")
		)
		(zone
			(layer "F.Cu")
			(hatch none 0.5)
			(connect_pads
				(clearance 0)
			)
			(min_thickness 0.25)
			(keepout
				(tracks allowed)
				(vias not_allowed)
				(pads allowed)
				(copperpour not_allowed)
				(footprints allowed)
			)
			(placement
				(enabled no)
				(sheetname "")
			)
			(fill
				(thermal_gap 0.5)
				(thermal_bridge_width 0.5)
				(island_removal_mode 0)
			)
			(polygon
				(pts
					(xy 455.9808 -28.702) (xy 455.9808 -29.718) (xy 457.6699 -29.718) (xy 457.6699 -28.702)
				)
			)
		)
		(zone
			(layer "F.Cu")
			(hatch none 0.5)
			(connect_pads
				(clearance 0)
			)
			(min_thickness 0.25)
			(keepout
				(tracks allowed)
				(vias not_allowed)
				(pads allowed)
				(copperpour not_allowed)
				(footprints allowed)
			)
			(placement
				(enabled no)
				(sheetname "")
			)
			(fill
				(thermal_gap 0.5)
				(thermal_bridge_width 0.5)
				(island_removal_mode 0)
			)
			(polygon
				(pts
					(xy 455.9808 -26.924) (xy 455.9808 -27.94) (xy 457.6699 -27.94) (xy 457.6699 -26.924)
				)
			)
		)
	)
	(footprint ""
		(layer "F.Cu")
		(at 0.130048 -110.259876)
		(property "Reference" "J10W1"
			(at 0 0 0)
			(layer "F.SilkS")
			(hide yes)
			(effects
				(font
					(size 1.27 1.27)
				)
			)
		)
		(property "Value" "*"
			(at -6.3881 -0.97155 0)
			(unlocked yes)
			(layer "F.Fab")
			(hide yes)
			(effects
				(font
					(size 0.889 0.889)
					(thickness 0.1524)
				)
			)
		)
		(property "Device Type" "LOTES-CON4-S1-GP_CONN-G7-LOTESA"
			(at -6.3881 -2.49555 0)
			(unlocked yes)
			(layer "F.Fab")
			(hide yes)
			(effects
				(font
					(size 0.889 0.889)
					(thickness 0.1524)
				)
			)
		)
		(duplicate_pad_numbers_are_jumpers no)
		(fp_line
			(start -5.334 -3.302)
			(end 5.334 -3.302)
			(stroke
				(width 0.508)
				(type default)
			)
			(layer "F.SilkS")
		)
		(fp_line
			(start -5.334 -3.1242)
			(end 5.334 -3.1242)
			(stroke
				(width 0.1524)
				(type default)
			)
			(layer "F.SilkS")
		)
		(fp_line
			(start -5.334 3.0226)
			(end -5.334 -3.1242)
			(stroke
				(width 0.1524)
				(type default)
			)
			(layer "F.SilkS")
		)
		(fp_line
			(start 4.191 3.16484)
			(end 5.461 3.16484)
			(stroke
				(width 0.4064)
				(type default)
			)
			(layer "F.SilkS")
		)
		(fp_line
			(start 5.334 -3.1242)
			(end 5.334 3.0226)
			(stroke
				(width 0.1524)
				(type default)
			)
			(layer "F.SilkS")
		)
		(fp_line
			(start 5.334 3.0226)
			(end -5.334 3.0226)
			(stroke
				(width 0.1524)
				(type default)
			)
			(layer "F.SilkS")
		)
		(fp_line
			(start 5.461 3.16484)
			(end 5.461 1.89484)
			(stroke
				(width 0.4064)
				(type default)
			)
			(layer "F.SilkS")
		)
		(fp_circle
			(center -3.81 0)
			(end -2.5527 0)
			(stroke
				(width 0.3048)
				(type default)
			)
			(fill no)
			(layer "F.SilkS")
		)
		(fp_circle
			(center -1.27 0)
			(end -0.0127 0)
			(stroke
				(width 0.3048)
				(type default)
			)
			(fill no)
			(layer "F.SilkS")
		)
		(fp_circle
			(center 1.27 0)
			(end 2.5273 0)
			(stroke
				(width 0.3048)
				(type default)
			)
			(fill no)
			(layer "F.SilkS")
		)
		(fp_circle
			(center 3.81 0)
			(end 5.0673 0)
			(stroke
				(width 0.3048)
				(type default)
			)
			(fill no)
			(layer "F.SilkS")
		)
		(fp_rect
			(start -5.08 2.54)
			(end 5.08 -2.8702)
			(stroke
				(width 0)
				(type default)
			)
			(fill no)
			(layer "F.CrtYd")
		)
		(fp_poly
			(pts
				(xy -5.588 3.2766) (xy -5.588 -3.3782) (xy 5.588 -3.3782) (xy 5.588 -0.00635) (xy 5.08 -0.00635)
				(xy 5.08 -2.8702) (xy -5.08 -2.8702) (xy -5.08 2.54) (xy 5.08 2.54) (xy 5.08 0.00635) (xy 5.588 0.00635)
				(xy 5.588 3.2766)
			)
			(stroke
				(width 0)
				(type default)
			)
			(fill no)
			(layer "F.CrtYd")
		)
		(fp_rect
			(start -5.588 3.2766)
			(end 5.588 -3.3782)
			(stroke
				(width 0)
				(type default)
			)
			(fill no)
			(layer "F.Fab")
		)
		(pad "" np_thru_hole circle
			(at -1.27 2.189988)
			(size 0.254 0.254)
			(drill 1.1684)
			(layers "*.Cu" "*.Mask")
			(clearance 0.8128)
			(thermal_gap 0.8128)
		)
		(pad "1" thru_hole circle
			(at 3.81 0)
			(size 1.8034 1.8034)
			(drill 1.1684)
			(layers "*.Cu" "*.Mask")
			(remove_unused_layers no)
			(net "GND")
			(clearance 0.1905)
			(thermal_gap 0.1905)
		)
		(pad "2" thru_hole circle
			(at 1.27 0)
			(size 1.8034 1.8034)
			(drill 1.1684)
			(layers "*.Cu" "*.Mask")
			(remove_unused_layers no)
			(net "P12V_FAN")
			(clearance 0.1905)
			(thermal_gap 0.1905)
		)
		(pad "3" thru_hole circle
			(at -1.27 0)
			(size 1.8034 1.8034)
			(drill 1.1684)
			(layers "*.Cu" "*.Mask")
			(remove_unused_layers no)
			(net "FAN_TACH2_CPU1_D1")
			(clearance 0.1905)
			(thermal_gap 0.1905)
		)
		(pad "4" thru_hole circle
			(at -3.81 0)
			(size 1.8034 1.8034)
			(drill 1.1684)
			(layers "*.Cu" "*.Mask")
			(remove_unused_layers no)
			(net "FAN_PWM_OUT_SYS1_R")
			(clearance 0.1905)
			(thermal_gap 0.1905)
		)
		(zone
			(layers "F.Cu" "B.Cu" "In1.Cu" "In2.Cu" "In3.Cu" "In4.Cu" "In5.Cu" "In6.Cu"
				"In7.Cu" "In8.Cu" "In9.Cu" "In10.Cu" "In11.Cu" "In12.Cu"
			)
			(hatch none 0.5)
			(connect_pads
				(clearance 0)
			)
			(min_thickness 0.25)
			(keepout
				(tracks not_allowed)
				(vias allowed)
				(pads allowed)
				(copperpour not_allowed)
				(footprints allowed)
			)
			(placement
				(enabled no)
				(sheetname "")
			)
			(fill
				(thermal_gap 0.5)
				(thermal_bridge_width 0.5)
				(island_removal_mode 0)
			)
			(polygon
				(pts
					(arc
						(start -0.250952 -108.069888)
						(mid -2.028952 -108.069888)
						(end -0.250952 -108.069888)
					)
				)
			)
		)
	)
)
